FILE_TYPE = MULTI_PHYS_TABLE;

PART 'DIODE_4_V1'
CLASS = DISCRETE

{========================================================================================}
:CLS_PN             = JEDEC_TYPE       |ALT_SYMBOLS          |DESCRIPTION    ;
{========================================================================================}
 'G122-10123-01'   = 'SOT143'  |'(SOT143)'  |'DIO,TVS,3.3VRWM,12A,SOT143-4L,SMT'  

END_PART

END.

